# SCM (Grand Teton) — schematic netlist excerpt (pin names and nets, part order shuffled) for the footprints in the layout excerpt that follows; sources: Cadence DE-HDL packaged netlist, KiCad conversion of 12092022_DA0F0TMDCD0_F0T_Management_Board_D_brd_V3_OCP.brd

R115  Q_RES  4.7K 1% EMPTY  pkg 0402LF  page 12 : A = PGPPA_BMC_AUX ; B = ESPI_HOST_LPC_BMC_LFRAME_N
R501  Q_RES  33.2 1% CHIP  pkg 0402LF  page 46 : A = SPI_SYS_R1_CLK ; B = SPI_SYS_R_CLK

(kicad_pcb
	(version 20260206)
	(generator "pcbnew")
	(generator_version "10.0")
	(general
		(thickness 1.6)
		(legacy_teardrops no)
	)
	(paper "A4")
	(title_block
		(title "12092022_DA0F0TMDCD0_F0T_Management_Board_D_brd_V3_OCP.brd")
		(comment 1 "Grand Teton / footprints 554-555 of 1440")
	)
	(layers
		(0 "F.Cu" signal "TOP")
		(4 "In1.Cu" signal "GND")
		(6 "In2.Cu" signal "IN1")
		(8 "In3.Cu" signal "GND1")
		(10 "In4.Cu" signal "IN2")
		(12 "In5.Cu" signal "VCC")
		(14 "In6.Cu" signal "VCC1")
		(16 "In7.Cu" signal "IN3")
		(18 "In8.Cu" signal "GND2")
		(20 "In9.Cu" signal "IN4")
		(22 "In10.Cu" signal "GND3")
		(2 "B.Cu" signal "BOTTOM")
		(9 "F.Adhes" user "F.Adhesive")
		(11 "B.Adhes" user "B.Adhesive")
		(13 "F.Paste" user "Package Geometry/Pastemask Top")
		(15 "B.Paste" user "Package Geometry/Pastemask Bottom")
		(5 "F.SilkS" user "Ref Des/Silkscreen Top")
		(7 "B.SilkS" user "Ref Des/Silkscreen Bottom")
		(1 "F.Mask" user "Board Geometry/Soldermask Top")
		(3 "B.Mask" user "Board Geometry/Soldermask Bottom")
		(17 "Dwgs.User" user "User.Drawings")
		(19 "Cmts.User" user "User.Comments")
		(21 "Eco1.User" user "User.Eco1")
		(23 "Eco2.User" user "User.Eco2")
		(25 "Edge.Cuts" user "Board Geometry/Outline")
		(27 "Margin" user)
		(31 "F.CrtYd" user "Package Geometry/Place Bound Top")
		(29 "B.CrtYd" user "Package Geometry/Place Bound Bottom")
		(35 "F.Fab" user "Ref Des/Assembly Top")
		(33 "B.Fab" user "Ref Des/Assembly Bottom")
	)
	(footprint ""
		(layer "F.Cu")
		(at 64.51854 -108.004356 90)
		(property "Reference" "R115"
			(at 0 0 90)
			(layer "F.SilkS")
			(hide yes)
			(effects
				(font
					(size 1.27 1.27)
				)
			)
		)
		(property "Value" ""
			(at 0 0 90)
			(layer "F.Fab")
			(effects
				(font
					(size 1.27 1.27)
				)
			)
		)
		(duplicate_pad_numbers_are_jumpers no)
		(fp_line
			(start 0.7874 -0.4064)
			(end 0.7874 0.4064)
			(stroke
				(width 0.1524)
				(type default)
			)
			(layer "F.SilkS")
		)
		(fp_line
			(start -0.7874 -0.4064)
			(end 0.7874 -0.4064)
			(stroke
				(width 0.1524)
				(type default)
			)
			(layer "F.SilkS")
		)
		(fp_line
			(start 0.7874 0.4064)
			(end -0.7874 0.4064)
			(stroke
				(width 0.1524)
				(type default)
			)
			(layer "F.SilkS")
		)
		(fp_line
			(start -0.7874 0.4064)
			(end -0.7874 -0.4064)
			(stroke
				(width 0.1524)
				(type default)
			)
			(layer "F.SilkS")
		)
		(fp_line
			(start -0.12065 -0.305054)
			(end -0.12065 -0.2794)
			(stroke
				(width 0.1)
				(type default)
			)
			(layer "F.Fab")
		)
		(fp_line
			(start -0.67945 -0.305054)
			(end -0.12065 -0.305054)
			(stroke
				(width 0.1)
				(type default)
			)
			(layer "F.Fab")
		)
		(fp_line
			(start 0.67945 -0.3048)
			(end 0.67945 0.3048)
			(stroke
				(width 0.1)
				(type default)
			)
			(layer "F.Fab")
		)
		(fp_line
			(start 0.12065 -0.3048)
			(end 0.67945 -0.3048)
			(stroke
				(width 0.1)
				(type default)
			)
			(layer "F.Fab")
		)
		(fp_line
			(start 0.12065 -0.2794)
			(end 0.12065 -0.3048)
			(stroke
				(width 0.1)
				(type default)
			)
			(layer "F.Fab")
		)
		(fp_line
			(start -0.12065 -0.2794)
			(end 0.12065 -0.2794)
			(stroke
				(width 0.1)
				(type default)
			)
			(layer "F.Fab")
		)
		(fp_line
			(start 0.120396 0.2794)
			(end -0.12065 0.2794)
			(stroke
				(width 0.1)
				(type default)
			)
			(layer "F.Fab")
		)
		(fp_line
			(start -0.12065 0.2794)
			(end -0.12065 0.3048)
			(stroke
				(width 0.1)
				(type default)
			)
			(layer "F.Fab")
		)
		(fp_line
			(start 0.67945 0.3048)
			(end 0.120396 0.3048)
			(stroke
				(width 0.1)
				(type default)
			)
			(layer "F.Fab")
		)
		(fp_line
			(start 0.120396 0.3048)
			(end 0.120396 0.2794)
			(stroke
				(width 0.1)
				(type default)
			)
			(layer "F.Fab")
		)
		(fp_line
			(start -0.12065 0.3048)
			(end -0.67945 0.3048)
			(stroke
				(width 0.1)
				(type default)
			)
			(layer "F.Fab")
		)
		(fp_line
			(start -0.67945 0.3048)
			(end -0.67945 -0.305054)
			(stroke
				(width 0.1)
				(type default)
			)
			(layer "F.Fab")
		)
		(pad "1" smd circle
			(at -0.40005 0 90)
			(size 0 0)
			(layers "F.Cu" "F.Mask" "F.Paste")
			(net "PGPPA_BMC_AUX")
		)
		(pad "2" smd circle
			(at 0.40005 0 90)
			(size 0 0)
			(layers "F.Cu" "F.Mask" "F.Paste")
			(net "ESPI_HOST_LPC_BMC_LFRAME_N")
		)
	)
	(footprint ""
		(layer "F.Cu")
		(at 55.7276 -105.664 180)
		(property "Reference" "R501"
			(at 0 0 180)
			(layer "F.SilkS")
			(hide yes)
			(effects
				(font
					(size 1.27 1.27)
				)
			)
		)
		(property "Value" ""
			(at 0 0 180)
			(layer "F.Fab")
			(effects
				(font
					(size 1.27 1.27)
				)
			)
		)
		(duplicate_pad_numbers_are_jumpers no)
		(fp_line
			(start 0.7874 0.4064)
			(end -0.7874 0.4064)
			(stroke
				(width 0.1524)
				(type default)
			)
			(layer "F.SilkS")
		)
		(fp_line
			(start 0.7874 -0.4064)
			(end 0.7874 0.4064)
			(stroke
				(width 0.1524)
				(type default)
			)
			(layer "F.SilkS")
		)
		(fp_line
			(start -0.7874 0.4064)
			(end -0.7874 -0.4064)
			(stroke
				(width 0.1524)
				(type default)
			)
			(layer "F.SilkS")
		)
		(fp_line
			(start -0.7874 -0.4064)
			(end 0.7874 -0.4064)
			(stroke
				(width 0.1524)
				(type default)
			)
			(layer "F.SilkS")
		)
		(fp_line
			(start 0.67945 0.3048)
			(end 0.120396 0.3048)
			(stroke
				(width 0.1)
				(type default)
			)
			(layer "F.Fab")
		)
		(fp_line
			(start 0.67945 -0.3048)
			(end 0.67945 0.3048)
			(stroke
				(width 0.1)
				(type default)
			)
			(layer "F.Fab")
		)
		(fp_line
			(start 0.12065 -0.2794)
			(end 0.12065 -0.3048)
			(stroke
				(width 0.1)
				(type default)
			)
			(layer "F.Fab")
		)
		(fp_line
			(start 0.12065 -0.3048)
			(end 0.67945 -0.3048)
			(stroke
				(width 0.1)
				(type default)
			)
			(layer "F.Fab")
		)
		(fp_line
			(start 0.120396 0.3048)
			(end 0.120396 0.2794)
			(stroke
				(width 0.1)
				(type default)
			)
			(layer "F.Fab")
		)
		(fp_line
			(start 0.120396 0.2794)
			(end -0.12065 0.2794)
			(stroke
				(width 0.1)
				(type default)
			)
			(layer "F.Fab")
		)
		(fp_line
			(start -0.12065 0.3048)
			(end -0.67945 0.3048)
			(stroke
				(width 0.1)
				(type default)
			)
			(layer "F.Fab")
		)
		(fp_line
			(start -0.12065 0.2794)
			(end -0.12065 0.3048)
			(stroke
				(width 0.1)
				(type default)
			)
			(layer "F.Fab")
		)
		(fp_line
			(start -0.12065 -0.2794)
			(end 0.12065 -0.2794)
			(stroke
				(width 0.1)
				(type default)
			)
			(layer "F.Fab")
		)
		(fp_line
			(start -0.12065 -0.305054)
			(end -0.12065 -0.2794)
			(stroke
				(width 0.1)
				(type default)
			)
			(layer "F.Fab")
		)
		(fp_line
			(start -0.67945 0.3048)
			(end -0.67945 -0.305054)
			(stroke
				(width 0.1)
				(type default)
			)
			(layer "F.Fab")
		)
		(fp_line
			(start -0.67945 -0.305054)
			(end -0.12065 -0.305054)
			(stroke
				(width 0.1)
				(type default)
			)
			(layer "F.Fab")
		)
		(pad "1" smd circle
			(at -0.40005 0 180)
			(size 0 0)
			(layers "F.Cu" "F.Mask" "F.Paste")
			(net "SPI_SYS_R1_CLK")
		)
		(pad "2" smd circle
			(at 0.40005 0 180)
			(size 0 0)
			(layers "F.Cu" "F.Mask" "F.Paste")
			(net "SPI_SYS_R_CLK")
		)
	)
)
